# SCM (Grand Teton) — schematic netlist excerpt (pin names and nets, part order shuffled) for the footprints in the layout excerpt that follows; sources: Cadence DE-HDL packaged netlist, KiCad conversion of 12092022_DA0F0TMDCD0_F0T_Management_Board_D_brd_V3_OCP.brd

C226  Q_CAP  1UF 25V 10% X6S  pkg C0402  page 51 : A = P12V_AUX ; B = GND
R465  Q_RES  33.2 1% CHIP  pkg 0402LF  page 13 : A = FM_FLASH_LATCH_N_R1 ; B = FM_FLASH_LATCH_N

(kicad_pcb
	(version 20260206)
	(generator "pcbnew")
	(generator_version "10.0")
	(general
		(thickness 1.6)
		(legacy_teardrops no)
	)
	(paper "A4")
	(title_block
		(title "12092022_DA0F0TMDCD0_F0T_Management_Board_D_brd_V3_OCP.brd")
		(comment 1 "Grand Teton / footprints 211-212 of 1440")
	)
	(layers
		(0 "F.Cu" signal "TOP")
		(4 "In1.Cu" signal "GND")
		(6 "In2.Cu" signal "IN1")
		(8 "In3.Cu" signal "GND1")
		(10 "In4.Cu" signal "IN2")
		(12 "In5.Cu" signal "VCC")
		(14 "In6.Cu" signal "VCC1")
		(16 "In7.Cu" signal "IN3")
		(18 "In8.Cu" signal "GND2")
		(20 "In9.Cu" signal "IN4")
		(22 "In10.Cu" signal "GND3")
		(2 "B.Cu" signal "BOTTOM")
		(9 "F.Adhes" user "F.Adhesive")
		(11 "B.Adhes" user "B.Adhesive")
		(13 "F.Paste" user "Package Geometry/Pastemask Top")
		(15 "B.Paste" user "Package Geometry/Pastemask Bottom")
		(5 "F.SilkS" user "Ref Des/Silkscreen Top")
		(7 "B.SilkS" user "Ref Des/Silkscreen Bottom")
		(1 "F.Mask" user "Board Geometry/Soldermask Top")
		(3 "B.Mask" user "Board Geometry/Soldermask Bottom")
		(17 "Dwgs.User" user "User.Drawings")
		(19 "Cmts.User" user "User.Comments")
		(21 "Eco1.User" user "User.Eco1")
		(23 "Eco2.User" user "User.Eco2")
		(25 "Edge.Cuts" user "Board Geometry/Outline")
		(27 "Margin" user)
		(31 "F.CrtYd" user "Package Geometry/Place Bound Top")
		(29 "B.CrtYd" user "Package Geometry/Place Bound Bottom")
		(35 "F.Fab" user "Ref Des/Assembly Top")
		(33 "B.Fab" user "Ref Des/Assembly Bottom")
	)
	(footprint ""
		(layer "F.Cu")
		(at 78.994 -82.55 -90)
		(property "Reference" "C226"
			(at 0 0 270)
			(layer "F.SilkS")
			(hide yes)
			(effects
				(font
					(size 1.27 1.27)
				)
			)
		)
		(property "Value" ""
			(at 0 0 270)
			(layer "F.Fab")
			(effects
				(font
					(size 1.27 1.27)
				)
			)
		)
		(duplicate_pad_numbers_are_jumpers no)
		(fp_line
			(start -0.7874 0.4064)
			(end -0.7874 -0.4064)
			(stroke
				(width 0.1524)
				(type default)
			)
			(layer "F.SilkS")
		)
		(fp_line
			(start 0.7874 0.4064)
			(end -0.7874 0.4064)
			(stroke
				(width 0.1524)
				(type default)
			)
			(layer "F.SilkS")
		)
		(fp_line
			(start -0.7874 -0.4064)
			(end 0.7874 -0.4064)
			(stroke
				(width 0.1524)
				(type default)
			)
			(layer "F.SilkS")
		)
		(fp_line
			(start 0.7874 -0.4064)
			(end 0.7874 0.4064)
			(stroke
				(width 0.1524)
				(type default)
			)
			(layer "F.SilkS")
		)
		(fp_line
			(start -0.67945 0.3048)
			(end -0.67945 -0.305054)
			(stroke
				(width 0.1)
				(type default)
			)
			(layer "F.Fab")
		)
		(fp_line
			(start -0.12065 0.3048)
			(end -0.67945 0.3048)
			(stroke
				(width 0.1)
				(type default)
			)
			(layer "F.Fab")
		)
		(fp_line
			(start 0.120396 0.3048)
			(end 0.120396 0.2794)
			(stroke
				(width 0.1)
				(type default)
			)
			(layer "F.Fab")
		)
		(fp_line
			(start 0.67945 0.3048)
			(end 0.120396 0.3048)
			(stroke
				(width 0.1)
				(type default)
			)
			(layer "F.Fab")
		)
		(fp_line
			(start -0.12065 0.2794)
			(end -0.12065 0.3048)
			(stroke
				(width 0.1)
				(type default)
			)
			(layer "F.Fab")
		)
		(fp_line
			(start 0.120396 0.2794)
			(end -0.12065 0.2794)
			(stroke
				(width 0.1)
				(type default)
			)
			(layer "F.Fab")
		)
		(fp_line
			(start -0.12065 -0.2794)
			(end 0.12065 -0.2794)
			(stroke
				(width 0.1)
				(type default)
			)
			(layer "F.Fab")
		)
		(fp_line
			(start 0.12065 -0.2794)
			(end 0.12065 -0.3048)
			(stroke
				(width 0.1)
				(type default)
			)
			(layer "F.Fab")
		)
		(fp_line
			(start 0.12065 -0.3048)
			(end 0.67945 -0.3048)
			(stroke
				(width 0.1)
				(type default)
			)
			(layer "F.Fab")
		)
		(fp_line
			(start 0.67945 -0.3048)
			(end 0.67945 0.3048)
			(stroke
				(width 0.1)
				(type default)
			)
			(layer "F.Fab")
		)
		(fp_line
			(start -0.67945 -0.305054)
			(end -0.12065 -0.305054)
			(stroke
				(width 0.1)
				(type default)
			)
			(layer "F.Fab")
		)
		(fp_line
			(start -0.12065 -0.305054)
			(end -0.12065 -0.2794)
			(stroke
				(width 0.1)
				(type default)
			)
			(layer "F.Fab")
		)
		(pad "1" smd circle
			(at -0.40005 0 270)
			(size 0 0)
			(layers "F.Cu" "F.Mask" "F.Paste")
			(net "P12V_AUX")
		)
		(pad "2" smd circle
			(at 0.40005 0 270)
			(size 0 0)
			(layers "F.Cu" "F.Mask" "F.Paste")
			(net "GND")
		)
	)
	(footprint ""
		(layer "F.Cu")
		(at 56.79948 -65.76822 180)
		(property "Reference" "R465"
			(at 0 0 180)
			(layer "F.SilkS")
			(hide yes)
			(effects
				(font
					(size 1.27 1.27)
				)
			)
		)
		(property "Value" ""
			(at 0 0 180)
			(layer "F.Fab")
			(effects
				(font
					(size 1.27 1.27)
				)
			)
		)
		(duplicate_pad_numbers_are_jumpers no)
		(fp_line
			(start 0.7874 0.4064)
			(end -0.7874 0.4064)
			(stroke
				(width 0.1524)
				(type default)
			)
			(layer "F.SilkS")
		)
		(fp_line
			(start 0.7874 -0.4064)
			(end 0.7874 0.4064)
			(stroke
				(width 0.1524)
				(type default)
			)
			(layer "F.SilkS")
		)
		(fp_line
			(start -0.7874 0.4064)
			(end -0.7874 -0.4064)
			(stroke
				(width 0.1524)
				(type default)
			)
			(layer "F.SilkS")
		)
		(fp_line
			(start -0.7874 -0.4064)
			(end 0.7874 -0.4064)
			(stroke
				(width 0.1524)
				(type default)
			)
			(layer "F.SilkS")
		)
		(fp_line
			(start 0.67945 0.3048)
			(end 0.120396 0.3048)
			(stroke
				(width 0.1)
				(type default)
			)
			(layer "F.Fab")
		)
		(fp_line
			(start 0.67945 -0.3048)
			(end 0.67945 0.3048)
			(stroke
				(width 0.1)
				(type default)
			)
			(layer "F.Fab")
		)
		(fp_line
			(start 0.12065 -0.2794)
			(end 0.12065 -0.3048)
			(stroke
				(width 0.1)
				(type default)
			)
			(layer "F.Fab")
		)
		(fp_line
			(start 0.12065 -0.3048)
			(end 0.67945 -0.3048)
			(stroke
				(width 0.1)
				(type default)
			)
			(layer "F.Fab")
		)
		(fp_line
			(start 0.120396 0.3048)
			(end 0.120396 0.2794)
			(stroke
				(width 0.1)
				(type default)
			)
			(layer "F.Fab")
		)
		(fp_line
			(start 0.120396 0.2794)
			(end -0.12065 0.2794)
			(stroke
				(width 0.1)
				(type default)
			)
			(layer "F.Fab")
		)
		(fp_line
			(start -0.12065 0.3048)
			(end -0.67945 0.3048)
			(stroke
				(width 0.1)
				(type default)
			)
			(layer "F.Fab")
		)
		(fp_line
			(start -0.12065 0.2794)
			(end -0.12065 0.3048)
			(stroke
				(width 0.1)
				(type default)
			)
			(layer "F.Fab")
		)
		(fp_line
			(start -0.12065 -0.2794)
			(end 0.12065 -0.2794)
			(stroke
				(width 0.1)
				(type default)
			)
			(layer "F.Fab")
		)
		(fp_line
			(start -0.12065 -0.305054)
			(end -0.12065 -0.2794)
			(stroke
				(width 0.1)
				(type default)
			)
			(layer "F.Fab")
		)
		(fp_line
			(start -0.67945 0.3048)
			(end -0.67945 -0.305054)
			(stroke
				(width 0.1)
				(type default)
			)
			(layer "F.Fab")
		)
		(fp_line
			(start -0.67945 -0.305054)
			(end -0.12065 -0.305054)
			(stroke
				(width 0.1)
				(type default)
			)
			(layer "F.Fab")
		)
		(pad "1" smd circle
			(at -0.40005 0 180)
			(size 0 0)
			(layers "F.Cu" "F.Mask" "F.Paste")
			(net "FM_FLASH_LATCH_N_R1")
		)
		(pad "2" smd circle
			(at 0.40005 0 180)
			(size 0 0)
			(layers "F.Cu" "F.Mask" "F.Paste")
			(net "FM_FLASH_LATCH_N")
		)
	)
)
